# S9S_MB_2U (Grand Teton) — schematic parts with pin connectivity, parts 1624–1624 of 6093; source: Cadence DE-HDL packaged netlist (pstxprt.dat, pstxnet.dat, pstchip.dat)

J31  SCONN288_ADR50017P130CC  SCONN288_ADR50017-P130CC IO  pkg DDR288S_1-1VXB  page 112
  1  VIN_BULK0  POWER  = P12V_S3_AUX_CPU1_NVDIMM
  2  RFU0  TRI  = TP_CHH_CPU1_DIMM1_FRU_0
  3  VIN_MGMT  POWER  = P3V3_AUX
  4  HSCL  IN  = I3C_SPD_DDREFGH_CPU1_LVC1_SCL_6
  5  HSDA  BI  = I3C_SPD_DDREFGH_CPU1_LVC1_SDA
  6  VSS0  POWER  = GND
  7  DQ0_A  BI  = M_H_CPU1_SA_DQ<0>
  8  VSS1  POWER  = GND
  9  DQ1_A  BI  = M_H_CPU1_SA_DQ<1>
  10  VSS2  POWER  = GND
  11  DQS0_A_T  BI  = M_H_CPU1_SA_DQS_DP<0>
  12  DQS0_A_C  BI  = M_H_CPU1_SA_DQS_DN<0>
  13  VSS3  POWER  = GND
  14  DQ4_A  BI  = M_H_CPU1_SA_DQ<4>
  15  VSS4  POWER  = GND
  16  DQ5_A  BI  = M_H_CPU1_SA_DQ<5>
  17  VSS5  POWER  = GND
  18  DQ8_A  BI  = M_H_CPU1_SA_DQ<8>
  19  VSS6  POWER  = GND
  20  DQ9_A  BI  = M_H_CPU1_SA_DQ<9>
  21  VSS7  POWER  = GND
  22  DQS1_A_T  BI  = M_H_CPU1_SA_DQS_DP<1>
  23  DQS1_A_C  BI  = M_H_CPU1_SA_DQS_DN<1>
  24  VSS8  POWER  = GND
  25  DQ12_A  BI  = M_H_CPU1_SA_DQ<12>
  26  VSS9  POWER  = GND
  27  DQ13_A  BI  = M_H_CPU1_SA_DQ<13>
  28  VSS10  POWER  = GND
  29  DQ16_A  BI  = M_H_CPU1_SA_DQ<16>
  30  VSS11  POWER  = GND
  31  DQ17_A  BI  = M_H_CPU1_SA_DQ<17>
  32  VSS12  POWER  = GND
  33  DQS2_A_T  BI  = M_H_CPU1_SA_DQS_DP<2>
  34  DQS2_A_C  BI  = M_H_CPU1_SA_DQS_DN<2>
  35  VSS13  POWER  = GND
  36  DQ20_A  BI  = M_H_CPU1_SA_DQ<20>
  37  VSS14  POWER  = GND
  38  DQ21_A  BI  = M_H_CPU1_SA_DQ<21>
  39  VSS15  POWER  = GND
  40  DQ24_A  BI  = M_H_CPU1_SA_DQ<24>
  41  VSS16  POWER  = GND
  42  DQ25_A  BI  = M_H_CPU1_SA_DQ<25>
  43  VSS17  POWER  = GND
  44  DQS3_A_T  BI  = M_H_CPU1_SA_DQS_DP<3>
  45  DQS3_A_C  BI  = M_H_CPU1_SA_DQS_DN<3>
  46  VSS18  POWER  = GND
  47  DQ28_A  BI  = M_H_CPU1_SA_DQ<28>
  48  VSS19  POWER  = GND
  49  DQ29_A  BI  = M_H_CPU1_SA_DQ<29>
  50  VSS20  POWER  = GND
  51  CB0_A  BI  = M_H_CPU1_SA_CB<0>
  52  VSS21  POWER  = GND
  53  CB1_A  BI  = M_H_CPU1_SA_CB<1>
  54  VSS22  POWER  = GND
  55  DQS4_A_T  BI  = M_H_CPU1_SA_DQS_DP<4>
  56  DQS4_A_C  BI  = M_H_CPU1_SA_DQS_DN<4>
  57  VSS23  POWER  = GND
  58  CB4_A  BI  = M_H_CPU1_SA_CB<4>
  59  VSS24  POWER  = GND
  60  CB5_A  BI  = M_H_CPU1_SA_CB<5>
  61  VSS25  POWER  = GND
  62  ALERT_N  OUT  = M_H_CPU1_ALERT_N
  63  VSS26  POWER  = GND
  64  CS0_A_N  IN  = M_H_CPU1_SA_CS_N<0>
  65  VSS27  POWER  = GND
  66  CA0_A  IN  = M_H_CPU1_SA_CA<0>
  67  VSS28  POWER  = GND
  68  CA2_A  IN  = M_H_CPU1_SA_CA<2>
  69  VSS29  POWER  = GND
  70  CA4_A  IN  = M_H_CPU1_SA_CA<4>
  71  VSS30  POWER  = GND
  72  CA6_A  IN  = M_H_CPU1_SA_CA<6>
  73  VSS31  POWER  = GND
  74  PAR_A  IN  = M_H_CPU1_SA_PAR
  75  VSS32  POWER  = GND
  76  CA0_B  IN  = M_H_CPU1_SB_CA<0>
  77  VSS33  POWER  = GND
  78  CA2_B  IN  = M_H_CPU1_SB_CA<2>
  79  VSS34  POWER  = GND
  80  CA4_B  IN  = M_H_CPU1_SB_CA<4>
  81  VSS35  POWER  = GND
  82  CA6_B  IN  = M_H_CPU1_SB_CA<6>
  83  VSS36  POWER  = GND
  84  CS0_B_N  IN  = M_H_CPU1_SB_CS_N<0>
  85  VSS37  POWER  = GND
  86  \lbd||rsp_a_n\  OUT  = M_H_CPU1_SA_RSP<0>
  87  \lbs||rsp_b_n\  OUT  = M_H_CPU1_SB_RSP<0>
  88  VSS38  POWER  = GND
  89  CB4_B  BI  = M_H_CPU1_SB_CB<4>
  90  VSS39  POWER  = GND
  91  CB5_B  BI  = M_H_CPU1_SB_CB<5>
  92  VSS40  POWER  = GND
  93  \dqs9_b_t||tdqs9_b_t||dbi4_b_n\  BI  = M_H_CPU1_SB_DQS_DP<9>
  94  \dqs9_b_c||tdqs9_b_c\  BI  = M_H_CPU1_SB_DQS_DN<9>
  95  VSS41  POWER  = GND
  96  CB0_B  BI  = M_H_CPU1_SB_CB<0>
  97  VSS42  POWER  = GND
  98  CB1_B  BI  = M_H_CPU1_SB_CB<1>
  99  VSS43  POWER  = GND
  100  DQ0_B  BI  = M_H_CPU1_SB_DQ<0>
  101  VSS44  POWER  = GND
  102  DQ1_B  BI  = M_H_CPU1_SB_DQ<1>
  103  VSS45  POWER  = GND
  104  DQS0_B_T  BI  = M_H_CPU1_SB_DQS_DP<0>
  105  DQS0_B_C  BI  = M_H_CPU1_SB_DQS_DN<0>
  106  VSS46  POWER  = GND
  107  DQ4_B  BI  = M_H_CPU1_SB_DQ<4>
  108  VSS47  POWER  = GND
  109  DQ5_B  BI  = M_H_CPU1_SB_DQ<5>
  110  VSS48  POWER  = GND
  111  DQ8_B  BI  = M_H_CPU1_SB_DQ<8>
  112  VSS49  POWER  = GND
  113  DQ9_B  BI  = M_H_CPU1_SB_DQ<9>
  114  VSS50  POWER  = GND
  115  DQS1_B_T  BI  = M_H_CPU1_SB_DQS_DP<1>
  116  DQS1_B_C  BI  = M_H_CPU1_SB_DQS_DN<1>
  117  VSS51  POWER  = GND
  118  DQ12_B  BI  = M_H_CPU1_SB_DQ<12>
  119  VSS52  POWER  = GND
  120  DQ13_B  BI  = M_H_CPU1_SB_DQ<13>
  121  VSS53  POWER  = GND
  122  DQ16_B  BI  = M_H_CPU1_SB_DQ<16>
  123  VSS54  POWER  = GND
  124  DQ17_B  BI  = M_H_CPU1_SB_DQ<17>
  125  VSS55  POWER  = GND
  126  DQS2_B_T  BI  = M_H_CPU1_SB_DQS_DP<2>
  127  DQS2_B_C  BI  = M_H_CPU1_SB_DQS_DN<2>
  128  VSS56  POWER  = GND
  129  DQ20_B  BI  = M_H_CPU1_SB_DQ<20>
  130  VSS57  POWER  = GND
  131  DQ21_B  BI  = M_H_CPU1_SB_DQ<21>
  132  VSS58  POWER  = GND
  133  DQ24_B  BI  = M_H_CPU1_SB_DQ<24>
  134  VSS59  POWER  = GND
  135  DQ25_B  BI  = M_H_CPU1_SB_DQ<25>
  136  VSS60  POWER  = GND
  137  DQS3_B_T  BI  = M_H_CPU1_SB_DQS_DP<3>
  138  DQS3_B_C  BI  = M_H_CPU1_SB_DQS_DN<3>
  139  VSS61  POWER  = GND
  140  DQ28_B  BI  = M_H_CPU1_SB_DQ<28>
  141  VSS62  POWER  = GND
  142  DQ29_B  BI  = M_H_CPU1_SB_DQ<29>
  143  VSS63  POWER  = GND
  144  RFU1  TRI  = TP_CHH_CPU1_DIMM1_FRU_1
  145  VIN_BULK1  POWER  = P12V_S3_AUX_CPU1_NVDIMM
  146  VIN_BULK2  POWER  = P12V_S3_AUX_CPU1_NVDIMM
  147  \pwr_good||fail_n\  BI  = PWRGD_CHH_CPU1_DIMM1
  148  HSA  IN  = PD_CHH_CPU1_DIMM1_SAA
  149  RFU2  TRI  = TP_CHH_CPU1_DIMM1_FRU_2
  150  RFU3  TRI  = TP_CHH_CPU1_DIMM1_FRU_3
  151  VSS64  POWER  = GND
  152  DQ2_A  BI  = M_H_CPU1_SA_DQ<2>
  153  VSS65  POWER  = GND
  154  DQ3_A  BI  = M_H_CPU1_SA_DQ<3>
  155  VSS66  POWER  = GND
  156  \dqs5_a_c||tdqs5_a_c||dqs5_a_t||tdqs5_a_t\  BI  = M_H_CPU1_SA_DQS_DN<5>
  157  \dqs5_a_t||tdqs5_a_t\  BI  = M_H_CPU1_SA_DQS_DP<5>
  158  VSS67  POWER  = GND
  159  DQ6_A  BI  = M_H_CPU1_SA_DQ<6>
  160  VSS68  POWER  = GND
  161  DQ7_A  BI  = M_H_CPU1_SA_DQ<7>
  162  VSS69  POWER  = GND
  163  DQ10_A  BI  = M_H_CPU1_SA_DQ<10>
  164  VSS70  POWER  = GND
  165  DQ11_A  BI  = M_H_CPU1_SA_DQ<11>
  166  VSS71  POWER  = GND
  167  \dqs6_a_c||tdqs6_a_c||dqs6_a_t||tdqs6_a_t\  BI  = M_H_CPU1_SA_DQS_DN<6>
  168  \dqs6_a_t||tdqs6_a_t\  BI  = M_H_CPU1_SA_DQS_DP<6>
  169  VSS72  POWER  = GND
  170  DQ14_A  BI  = M_H_CPU1_SA_DQ<14>
  171  VSS73  POWER  = GND
  172  DQ15_A  BI  = M_H_CPU1_SA_DQ<15>
  173  VSS74  POWER  = GND
  174  DQ18_A  BI  = M_H_CPU1_SA_DQ<18>
  175  VSS75  POWER  = GND
  176  DQ19_A  BI  = M_H_CPU1_SA_DQ<19>
  177  VSS76  POWER  = GND
  178  \dqs7_a_c||tdqs7_a_c\  BI  = M_H_CPU1_SA_DQS_DN<7>
  179  \dqs7_a_t||tdqs7_a_t\  BI  = M_H_CPU1_SA_DQS_DP<7>
  180  VSS77  POWER  = GND
  181  DQ22_A  BI  = M_H_CPU1_SA_DQ<22>
  182  VSS78  POWER  = GND
  183  DQ23_A  BI  = M_H_CPU1_SA_DQ<23>
  184  VSS79  POWER  = GND
  185  DQ26_A  BI  = M_H_CPU1_SA_DQ<26>
  186  VSS80  POWER  = GND
  187  DQ27_A  BI  = M_H_CPU1_SA_DQ<27>
  188  VSS81  POWER  = GND
  189  \dqs8_a_c||tdqs8_a_c\  BI  = M_H_CPU1_SA_DQS_DN<8>
  190  \dqs8_a_t||tdqs8_a_t\  BI  = M_H_CPU1_SA_DQS_DP<8>
  191  VSS82  POWER  = GND
  192  DQ30_A  BI  = M_H_CPU1_SA_DQ<30>
  193  VSS83  POWER  = GND
  194  DQ31_A  BI  = M_H_CPU1_SA_DQ<31>
  195  VSS84  POWER  = GND
  196  CB2_A  BI  = M_H_CPU1_SA_CB<2>
  197  VSS85  POWER  = GND
  198  CB3_A  BI  = M_H_CPU1_SA_CB<3>
  199  VSS86  POWER  = GND
  200  \dqs9_a_c||tdqs9_a_c\  BI  = M_H_CPU1_SA_DQS_DN<9>
  201  \dqs9_a_t||tdqs9_a_t\  BI  = M_H_CPU1_SA_DQS_DP<9>
  202  VSS87  POWER  = GND
  203  CB6_A  BI  = M_H_CPU1_SA_CB<6>
  204  VSS88  POWER  = GND
  205  CB7_A  BI  = M_H_CPU1_SA_CB<7>
  206  VSS89  POWER  = GND
  207  RESET_N  IN  = RST_M_GH_CPU1_FPGA_N
  208  VSS90  POWER  = GND
  209  CS1_A_N  IN  = M_H_CPU1_SA_CS_N<1>
  210  VSS91  POWER  = GND
  211  CA1_A  IN  = M_H_CPU1_SA_CA<1>
  212  VSS92  POWER  = GND
  213  CA3_A  IN  = M_H_CPU1_SA_CA<3>
  214  VSS93  POWER  = GND
  215  CA5_A  IN  = M_H_CPU1_SA_CA<5>
  216  VSS94  POWER  = GND
  217  CK_T  IN  = M_H_CPU1_CLK_DP<0>
  218  CK_C  IN  = M_H_CPU1_CLK_DN<0>
  219  VSS95  POWER  = GND
  220  RFU4  TRI  = TP_CHH_CPU1_DIMM1_FRU_4
  221  CA1_B  IN  = M_H_CPU1_SB_CA<1>
  222  VSS96  POWER  = GND
  223  CA3_B  IN  = M_H_CPU1_SB_CA<3>
  224  VSS97  POWER  = GND
  225  CA5_B  IN  = M_H_CPU1_SB_CA<5>
  226  VSS98  POWER  = GND
  227  PAR_B  IN  = M_H_CPU1_SB_PAR
  228  VSS99  POWER  = GND
  229  CS1_B_N  IN  = M_H_CPU1_SB_CS_N<1>
  230  VSS100  POWER  = GND
  231  RFU5  TRI  = TP_CHH_CPU1_DIMM1_FRU_5
  232  RFU6  TRI  = TP_CHH_CPU1_DIMM1_FRU_6
  233  VSS101  POWER  = GND
  234  CB6_B  BI  = M_H_CPU1_SB_CB<6>
  235  VSS102  POWER  = GND
  236  CB7_B  BI  = M_H_CPU1_SB_CB<7>
  237  VSS103  POWER  = GND
  238  DQS4_B_C  BI  = M_H_CPU1_SB_DQS_DN<4>
  239  DQS4_B_T  BI  = M_H_CPU1_SB_DQS_DP<4>
  240  VSS104  POWER  = GND
  241  CB2_B  BI  = M_H_CPU1_SB_CB<2>
  242  VSS105  POWER  = GND
  243  CB3_B  BI  = M_H_CPU1_SB_CB<3>
  244  VSS106  POWER  = GND
  245  DQ2_B  BI  = M_H_CPU1_SB_DQ<2>
  246  VSS107  POWER  = GND
  247  DQ3_B  BI  = M_H_CPU1_SB_DQ<3>
  248  VSS108  POWER  = GND
  249  \dqs5_b_c||tdqs5_b_c\  BI  = M_H_CPU1_SB_DQS_DN<5>
  250  \dqs5_b_t||tdqs5_b_t\  BI  = M_H_CPU1_SB_DQS_DP<5>
  251  VSS109  POWER  = GND
  252  DQ6_B  BI  = M_H_CPU1_SB_DQ<6>
  253  VSS110  POWER  = GND
  254  DQ7_B  BI  = M_H_CPU1_SB_DQ<7>
  255  VSS111  POWER  = GND
  256  DQ10_B  BI  = M_H_CPU1_SB_DQ<10>
  257  VSS112  POWER  = GND
  258  DQ11_B  BI  = M_H_CPU1_SB_DQ<11>
  259  VSS113  POWER  = GND
  260  \dqs6_b_c||tdqs6_b_c\  BI  = M_H_CPU1_SB_DQS_DN<6>
  261  \dqs6_b_t||tdqs6_b_t\  BI  = M_H_CPU1_SB_DQS_DP<6>
  262  VSS114  POWER  = GND
  263  DQ14_B  BI  = M_H_CPU1_SB_DQ<14>
  264  VSS115  POWER  = GND
  265  DQ15_B  BI  = M_H_CPU1_SB_DQ<15>
  266  VSS116  POWER  = GND
  267  DQ18_B  BI  = M_H_CPU1_SB_DQ<18>
  268  VSS117  POWER  = GND
  269  DQ19_B  BI  = M_H_CPU1_SB_DQ<19>
  270  VSS118  POWER  = GND
  271  \dqs7_b_c||tdqs7_b_c\  BI  = M_H_CPU1_SB_DQS_DN<7>
  272  \dqs7_b_t||tdqs7_b_t\  BI  = M_H_CPU1_SB_DQS_DP<7>
  273  VSS119  POWER  = GND
  274  DQ22_B  BI  = M_H_CPU1_SB_DQ<22>
  275  VSS120  POWER  = GND
  276  DQ23_B  BI  = M_H_CPU1_SB_DQ<23>
  277  VSS121  POWER  = GND
  278  DQ26_B  BI  = M_H_CPU1_SB_DQ<26>
  279  VSS122  POWER  = GND
  280  DQ27_B  BI  = M_H_CPU1_SB_DQ<27>
  281  VSS123  POWER  = GND
  282  \dqs8_b_c||tdqs8_b_c\  BI  = M_H_CPU1_SB_DQS_DN<8>
  283  \dqs8_b_t||tdqs8_b_t\  BI  = M_H_CPU1_SB_DQS_DP<8>
  284  VSS124  POWER  = GND
  285  DQ30_B  BI  = M_H_CPU1_SB_DQ<30>
  286  VSS125  POWER  = GND
  287  DQ31_B  BI  = M_H_CPU1_SB_DQ<31>
  288  VSS126  POWER  = GND
  G1  G1  POWER  = GND
  G2  G2  POWER  = GND
  G3  G3  POWER  = GND
